%FSTAX25Y25*%
%MOIN*%
%SFA1B1*%

%IPPOS*%
%ADD14C,0.010000*%
%ADD18C,0.006000*%
%LNgrandmaster-1*%
%LPD*%
G54D14*
X0858258Y0885761D02*
D01*
X0858243Y0886186*
X0858198Y088661*
X0858124Y0887029*
X0858021Y0887442*
X085789Y0887848*
X085773Y0888242*
X0857543Y0888625*
X085733Y0888994*
X0857092Y0889347*
X085683Y0889683*
X0856545Y0889999*
X0856239Y0890295*
X0855912Y0890569*
X0855568Y0890819*
X0855207Y0891045*
X085483Y0891245*
X0854441Y0891418*
X0854041Y0891564*
X0853632Y0891681*
X0853215Y089177*
X0852793Y0891829*
X0852368Y0891859*
X0851943*
X0851518Y0891829*
X0851096Y089177*
X0850679Y0891681*
X085027Y0891564*
X084987Y0891418*
X0849481Y0891245*
X0849105Y0891045*
X0848743Y0890819*
X0848399Y0890569*
X0848072Y0890295*
X0847766Y0889999*
X0847481Y0889683*
X0847219Y0889347*
X0846981Y0888994*
X0846768Y0888625*
X0846581Y0888242*
X0846421Y0887848*
X084629Y0887442*
X0846187Y0887029*
X0846113Y088661*
X0846068Y0886186*
X0846054Y0885761*
X0846068Y0885335*
X0846113Y0884911*
X0846187Y0884492*
X084629Y0884079*
X0846421Y0883673*
X0846581Y0883279*
X0846768Y0882896*
X0846981Y0882527*
X0847219Y0882174*
X0847481Y0881838*
X0847766Y0881522*
X0848072Y0881226*
X0848399Y0880952*
X0848743Y0880702*
X0849105Y0880476*
X0849481Y0880276*
X084987Y0880103*
X085027Y0879957*
X0850679Y087984*
X0851096Y0879751*
X0851518Y0879692*
X0851943Y0879662*
X0852368*
X0852793Y0879692*
X0853215Y0879751*
X0853632Y087984*
X0854041Y0879957*
X0854441Y0880103*
X085483Y0880276*
X0855207Y0880476*
X0855568Y0880702*
X0855912Y0880952*
X0856239Y0881226*
X0856545Y0881522*
X085683Y0881838*
X0857092Y0882174*
X085733Y0882527*
X0857543Y0882896*
X085773Y0883279*
X085789Y0883673*
X0858021Y0884079*
X0858124Y0884492*
X0858198Y0884911*
X0858243Y0885335*
X0858258Y0885761*
Y0783398D02*
D01*
X0858243Y0783823*
X0858198Y0784247*
X0858124Y0784666*
X0858021Y0785079*
X085789Y0785485*
X085773Y0785879*
X0857543Y0786262*
X085733Y0786631*
X0857092Y0786984*
X085683Y078732*
X0856545Y0787636*
X0856239Y0787932*
X0855912Y0788206*
X0855568Y0788456*
X0855207Y0788682*
X085483Y0788882*
X0854441Y0789055*
X0854041Y0789201*
X0853632Y0789318*
X0853215Y0789407*
X0852793Y0789466*
X0852368Y0789496*
X0851943*
X0851518Y0789466*
X0851096Y0789407*
X0850679Y0789318*
X085027Y0789201*
X084987Y0789055*
X0849481Y0788882*
X0849105Y0788682*
X0848743Y0788456*
X0848399Y0788206*
X0848072Y0787932*
X0847766Y0787636*
X0847481Y078732*
X0847219Y0786984*
X0846981Y0786631*
X0846768Y0786262*
X0846581Y0785879*
X0846421Y0785485*
X084629Y0785079*
X0846187Y0784666*
X0846113Y0784247*
X0846068Y0783823*
X0846054Y0783398*
X0846068Y0782972*
X0846113Y0782548*
X0846187Y0782129*
X084629Y0781716*
X0846421Y078131*
X0846581Y0780916*
X0846768Y0780533*
X0846981Y0780164*
X0847219Y0779811*
X0847481Y0779475*
X0847766Y0779159*
X0848072Y0778863*
X0848399Y0778589*
X0848743Y0778339*
X0849105Y0778113*
X0849481Y0777913*
X084987Y077774*
X085027Y0777594*
X0850679Y0777477*
X0851096Y0777388*
X0851518Y0777329*
X0851943Y0777299*
X0852368*
X0852793Y0777329*
X0853215Y0777388*
X0853632Y0777477*
X0854041Y0777594*
X0854441Y077774*
X085483Y0777913*
X0855207Y0778113*
X0855568Y0778339*
X0855912Y0778589*
X0856239Y0778863*
X0856545Y0779159*
X085683Y0779475*
X0857092Y0779811*
X085733Y0780164*
X0857543Y0780533*
X085773Y0780916*
X085789Y078131*
X0858021Y0781716*
X0858124Y0782129*
X0858198Y0782548*
X0858243Y0782972*
X0858258Y0783398*
X0620069D02*
D01*
X0620054Y0783823*
X0620009Y0784247*
X0619935Y0784666*
X0619832Y0785079*
X0619701Y0785485*
X0619541Y0785879*
X0619354Y0786262*
X0619141Y0786631*
X0618903Y0786984*
X0618641Y078732*
X0618356Y0787636*
X061805Y0787932*
X0617723Y0788206*
X0617379Y0788456*
X0617018Y0788682*
X0616641Y0788882*
X0616252Y0789055*
X0615852Y0789201*
X0615443Y0789318*
X0615026Y0789407*
X0614604Y0789466*
X0614179Y0789496*
X0613754*
X0613329Y0789466*
X0612907Y0789407*
X061249Y0789318*
X0612081Y0789201*
X0611681Y0789055*
X0611292Y0788882*
X0610916Y0788682*
X0610554Y0788456*
X061021Y0788206*
X0609883Y0787932*
X0609577Y0787636*
X0609292Y078732*
X060903Y0786984*
X0608792Y0786631*
X0608579Y0786262*
X0608392Y0785879*
X0608232Y0785485*
X0608101Y0785079*
X0607998Y0784666*
X0607924Y0784247*
X0607879Y0783823*
X0607865Y0783398*
X0607879Y0782972*
X0607924Y0782548*
X0607998Y0782129*
X0608101Y0781716*
X0608232Y078131*
X0608392Y0780916*
X0608579Y0780533*
X0608792Y0780164*
X060903Y0779811*
X0609292Y0779475*
X0609577Y0779159*
X0609883Y0778863*
X061021Y0778589*
X0610554Y0778339*
X0610916Y0778113*
X0611292Y0777913*
X0611681Y077774*
X0612081Y0777594*
X061249Y0777477*
X0612907Y0777388*
X0613329Y0777329*
X0613754Y0777299*
X0614179*
X0614604Y0777329*
X0615026Y0777388*
X0615443Y0777477*
X0615852Y0777594*
X0616252Y077774*
X0616641Y0777913*
X0617018Y0778113*
X0617379Y0778339*
X0617723Y0778589*
X061805Y0778863*
X0618356Y0779159*
X0618641Y0779475*
X0618903Y0779811*
X0619141Y0780164*
X0619354Y0780533*
X0619541Y0780916*
X0619701Y078131*
X0619832Y0781716*
X0619935Y0782129*
X0620009Y0782548*
X0620054Y0782972*
X0620069Y0783398*
Y0885761D02*
D01*
X0620054Y0886186*
X0620009Y088661*
X0619935Y0887029*
X0619832Y0887442*
X0619701Y0887848*
X0619541Y0888242*
X0619354Y0888625*
X0619141Y0888994*
X0618903Y0889347*
X0618641Y0889683*
X0618356Y0889999*
X061805Y0890295*
X0617723Y0890569*
X0617379Y0890819*
X0617018Y0891045*
X0616641Y0891245*
X0616252Y0891418*
X0615852Y0891564*
X0615443Y0891681*
X0615026Y089177*
X0614604Y0891829*
X0614179Y0891859*
X0613754*
X0613329Y0891829*
X0612907Y089177*
X061249Y0891681*
X0612081Y0891564*
X0611681Y0891418*
X0611292Y0891245*
X0610916Y0891045*
X0610554Y0890819*
X061021Y0890569*
X0609883Y0890295*
X0609577Y0889999*
X0609292Y0889683*
X060903Y0889347*
X0608792Y0888994*
X0608579Y0888625*
X0608392Y0888242*
X0608232Y0887848*
X0608101Y0887442*
X0607998Y0887029*
X0607924Y088661*
X0607879Y0886186*
X0607865Y0885761*
X0607879Y0885335*
X0607924Y0884911*
X0607998Y0884492*
X0608101Y0884079*
X0608232Y0883673*
X0608392Y0883279*
X0608579Y0882896*
X0608792Y0882527*
X060903Y0882174*
X0609292Y0881838*
X0609577Y0881522*
X0609883Y0881226*
X061021Y0880952*
X0610554Y0880702*
X0610916Y0880476*
X0611292Y0880276*
X0611681Y0880103*
X0612081Y0879957*
X061249Y087984*
X0612907Y0879751*
X0613329Y0879692*
X0613754Y0879662*
X0614179*
X0614604Y0879692*
X0615026Y0879751*
X0615443Y087984*
X0615852Y0879957*
X0616252Y0880103*
X0616641Y0880276*
X0617018Y0880476*
X0617379Y0880702*
X0617723Y0880952*
X061805Y0881226*
X0618356Y0881522*
X0618641Y0881838*
X0618903Y0882174*
X0619141Y0882527*
X0619354Y0882896*
X0619541Y0883279*
X0619701Y0883673*
X0619832Y0884079*
X0619935Y0884492*
X0620009Y0884911*
X0620054Y0885335*
X0620069Y0885761*
X0865305Y077208D02*
Y0897079D01*
X0600817Y077208D02*
X0865305D01*
X0600817D02*
Y0897079D01*
X0865305*
X0823871Y0796465D02*
X0824621Y0797215D01*
X082612*
X082687Y0796465*
Y0793466*
X082612Y0792717*
X0824621*
X0823871Y0793466*
X0822371Y0796465D02*
X0821622Y0797215D01*
X0820122*
X0819372Y0796465*
Y0795716*
X0820122Y0794966*
X0819372Y0794216*
Y0793466*
X0820122Y0792717*
X0821622*
X0822371Y0793466*
Y0794216*
X0821622Y0794966*
X0822371Y0795716*
Y0796465*
X0821622Y0794966D02*
X0820122D01*
X0817873Y0797215D02*
X0814874D01*
Y0796465*
X0817873Y0793466*
Y0792717*
X0828005Y0786524D02*
X0828755Y0787274D01*
X0830254*
X0831004Y0786524*
Y0783525*
X0830254Y0782776*
X0828755*
X0828005Y0783525*
X0826505Y0786524D02*
X0825756Y0787274D01*
X0824256*
X0823506Y0786524*
Y0785775*
X0824256Y0785025*
X0823506Y0784275*
Y0783525*
X0824256Y0782776*
X0825756*
X0826505Y0783525*
Y0784275*
X0825756Y0785025*
X0826505Y0785775*
Y0786524*
X0825756Y0785025D02*
X0824256D01*
X0822007Y0786524D02*
X0821257Y0787274D01*
X0819758*
X0819008Y0786524*
Y0785775*
X0819758Y0785025*
X0819008Y0784275*
Y0783525*
X0819758Y0782776*
X0821257*
X0822007Y0783525*
Y0784275*
X0821257Y0785025*
X0822007Y0785775*
Y0786524*
X0821257Y0785025D02*
X0819758D01*
X0863198Y0811464D02*
X0863947Y0810714D01*
Y0809214*
X0863198Y0808465*
X0860199*
X0859449Y0809214*
Y0810714*
X0860199Y0811464*
X0863198Y0812963D02*
X0863947Y0813713D01*
Y0815212*
X0863198Y0815962*
X0862448*
X0861698Y0815212*
X0860948Y0815962*
X0860199*
X0859449Y0815212*
Y0813713*
X0860199Y0812963*
X0860948*
X0861698Y0813713*
X0862448Y0812963*
X0863198*
X0861698Y0813713D02*
Y0815212D01*
X0860199Y0817462D02*
X0859449Y0818211D01*
Y0819711*
X0860199Y0820461*
X0863198*
X0863947Y0819711*
Y0818211*
X0863198Y0817462*
X0862448*
X0861698Y0818211*
Y0820461*
X0882999Y0803899D02*
X0883749Y0804649D01*
X0885248*
X0885998Y0803899*
Y08009*
X0885248Y0800151*
X0883749*
X0882999Y08009*
X0881499D02*
X088075Y0800151D01*
X087925*
X08785Y08009*
Y0803899*
X087925Y0804649*
X088075*
X0881499Y0803899*
Y080315*
X088075Y08024*
X08785*
X0877001Y0803899D02*
X0876251Y0804649D01*
X0874752*
X0874002Y0803899*
Y08009*
X0874752Y0800151*
X0876251*
X0877001Y08009*
Y0803899*
X08648Y0905099D02*
Y090135D01*
X086405Y09006*
X0862551*
X0861801Y090135*
Y0905099*
X0860301Y09006D02*
X0858802D01*
X0859552*
Y0905099*
X0860301Y0904349*
X0854303Y09006D02*
Y0905099D01*
X0856553Y0902849*
X0853554*
X0905299Y0547501D02*
X0906049Y0546751D01*
Y0545252*
X0905299Y0544502*
X09023*
X0901551Y0545252*
Y0546751*
X09023Y0547501*
X0906049Y0552D02*
Y0549001D01*
X09038*
X090455Y05505*
Y055125*
X09038Y0552*
X09023*
X0901551Y055125*
Y054975*
X09023Y0549001*
X0905299Y0553499D02*
X0906049Y0554249D01*
Y0555748*
X0905299Y0556498*
X090455*
X09038Y0555748*
Y0554999*
Y0555748*
X090305Y0556498*
X09023*
X0901551Y0555748*
Y0554249*
X09023Y0553499*
X0898699Y0547501D02*
X0899449Y0546751D01*
Y0545252*
X0898699Y0544502*
X08957*
X0894951Y0545252*
Y0546751*
X08957Y0547501*
X0899449Y0552D02*
Y0549001D01*
X08972*
X089795Y05505*
Y055125*
X08972Y0552*
X08957*
X0894951Y055125*
Y054975*
X08957Y0549001*
X0894951Y0556498D02*
Y0553499D01*
X089795Y0556498*
X0898699*
X0899449Y0555748*
Y0554249*
X0898699Y0553499*
X08892Y0547501D02*
X0889949Y0546751D01*
Y0545252*
X08892Y0544502*
X0886201*
X0885451Y0545252*
Y0546751*
X0886201Y0547501*
X0889949Y0552D02*
Y0549001D01*
X08877*
X088845Y05505*
Y055125*
X08877Y0552*
X0886201*
X0885451Y055125*
Y054975*
X0886201Y0549001*
X0885451Y0553499D02*
Y0554999D01*
Y0554249*
X0889949*
X08892Y0553499*
X08821Y0547501D02*
X0882849Y0546751D01*
Y0545252*
X08821Y0544502*
X0879101*
X0878351Y0545252*
Y0546751*
X0879101Y0547501*
X0882849Y0552D02*
Y0549001D01*
X08806*
X088135Y05505*
Y055125*
X08806Y0552*
X0879101*
X0878351Y055125*
Y054975*
X0879101Y0549001*
X08821Y0553499D02*
X0882849Y0554249D01*
Y0555748*
X08821Y0556498*
X0879101*
X0878351Y0555748*
Y0554249*
X0879101Y0553499*
X08821*
X0872999Y0547501D02*
X0873749Y0546751D01*
Y0545252*
X0872999Y0544502*
X087*
X0869251Y0545252*
Y0546751*
X087Y0547501*
X0869251Y055125D02*
X0873749D01*
X08715Y0549001*
Y0552*
X087Y0553499D02*
X0869251Y0554249D01*
Y0555748*
X087Y0556498*
X0872999*
X0873749Y0555748*
Y0554249*
X0872999Y0553499*
X087225*
X08715Y0554249*
Y0556498*
X0866199Y0547501D02*
X0866949Y0546751D01*
Y0545252*
X0866199Y0544502*
X08632*
X0862451Y0545252*
Y0546751*
X08632Y0547501*
X0862451Y055125D02*
X0866949D01*
X08647Y0549001*
Y0552*
X0866199Y0553499D02*
X0866949Y0554249D01*
Y0555748*
X0866199Y0556498*
X086545*
X08647Y0555748*
X086395Y0556498*
X08632*
X0862451Y0555748*
Y0554249*
X08632Y0553499*
X086395*
X08647Y0554249*
X086545Y0553499*
X0866199*
X08647Y0554249D02*
Y0555748D01*
X08547Y0547501D02*
X0855449Y0546751D01*
Y0545252*
X08547Y0544502*
X08517*
X0850951Y0545252*
Y0546751*
X08517Y0547501*
X0850951Y055125D02*
X0855449D01*
X08532Y0549001*
Y0552*
X0855449Y0553499D02*
Y0556498D01*
X08547*
X08517Y0553499*
X0850951*
X0847799Y0547501D02*
X0848549Y0546751D01*
Y0545252*
X0847799Y0544502*
X08448*
X0844051Y0545252*
Y0546751*
X08448Y0547501*
X0844051Y055125D02*
X0848549D01*
X08463Y0549001*
Y0552*
X0848549Y0556498D02*
X0847799Y0554999D01*
X08463Y0553499*
X08448*
X0844051Y0554249*
Y0555748*
X08448Y0556498*
X084555*
X08463Y0555748*
Y0553499*
X0840363Y054916D02*
X0841113Y0548411D01*
Y0546911*
X0840363Y0546161*
X0837364*
X0836614Y0546911*
Y0548411*
X0837364Y054916*
X0836614Y0552909D02*
X0841113D01*
X0838863Y055066*
Y0553659*
X0841113Y0558157D02*
Y0555159D01*
X0838863*
X0839613Y0556658*
Y0557408*
X0838863Y0558157*
X0837364*
X0836614Y0557408*
Y0555908*
X0837364Y0555159*
X0833375Y0549357D02*
X0834124Y0548607D01*
Y0547108*
X0833375Y0546358*
X0830376*
X0829626Y0547108*
Y0548607*
X0830376Y0549357*
X0829626Y0553106D02*
X0834124D01*
X0831875Y0550857*
Y0553856*
X0829626Y0557605D02*
X0834124D01*
X0831875Y0555355*
Y0558354*
G54D18*
X08323Y07986D02*
X08383D01*
X08323Y0791D02*
X08383D01*
X08661Y07981D02*
Y08041D01*
X08585Y07981D02*
Y08041D01*
M02*